# BASEBOARD_FAB2 (Tioga Pass) — schematic netlist excerpt (pin names and nets, part order shuffled) for the footprints in the layout excerpt that follows; sources: Cadence DE-HDL packaged netlist, KiCad conversion of Wiwynn_Tioga_Pass_MB.brd

R9A5  RES  20.0K 1% CHIP  pkg 0402  page 155 : A = P5V_STBY ; B = FM_UART_SWITCH_N
R10W6  RES  100.0 1% CHIP  pkg 0402  page 251 : A = PUMP_TACH1 ; B = PUMP_TACH1_R
R1A3  RES  68.1K 1% EMPTY  pkg 0402  page 227 : A = VR_PVDDQ_KLM_PH1_OCSET ; B = GND

(kicad_pcb
	(version 20260206)
	(generator "pcbnew")
	(generator_version "10.0")
	(general
		(thickness 1.6)
		(legacy_teardrops no)
	)
	(paper "A4")
	(title_block
		(title "Wiwynn_Tioga_Pass_MB.brd")
		(comment 1 "Tioga Pass / footprints 25-27 of 4770")
	)
	(layers
		(0 "F.Cu" signal "TOP")
		(4 "In1.Cu" signal "L2GND")
		(6 "In2.Cu" signal "L3")
		(8 "In3.Cu" signal "L4GND")
		(10 "In4.Cu" signal "L5")
		(12 "In5.Cu" signal "L6GND")
		(14 "In6.Cu" signal "L7VCC")
		(16 "In7.Cu" signal "L8VCC")
		(18 "In8.Cu" signal "L9GND")
		(20 "In9.Cu" signal "L10")
		(22 "In10.Cu" signal "L11GND")
		(24 "In11.Cu" signal "L12")
		(26 "In12.Cu" signal "L13GND")
		(2 "B.Cu" signal "BOTTOM")
		(9 "F.Adhes" user "F.Adhesive")
		(11 "B.Adhes" user "B.Adhesive")
		(13 "F.Paste" user "Package Geometry/Pastemask Top")
		(15 "B.Paste" user "Package Geometry/Pastemask Bottom")
		(5 "F.SilkS" user "Ref Des/Silkscreen Top")
		(7 "B.SilkS" user "Ref Des/Silkscreen Bottom")
		(1 "F.Mask" user "Board Geometry/Soldermask Top")
		(3 "B.Mask" user "Board Geometry/Soldermask Bottom")
		(17 "Dwgs.User" user "User.Drawings")
		(19 "Cmts.User" user "User.Comments")
		(21 "Eco1.User" user "User.Eco1")
		(23 "Eco2.User" user "User.Eco2")
		(25 "Edge.Cuts" user "Board Geometry/Outline")
		(27 "Margin" user)
		(31 "F.CrtYd" user "Package Geometry/Place Bound Top")
		(29 "B.CrtYd" user "Package Geometry/Place Bound Bottom")
		(35 "F.Fab" user "Ref Des/Assembly Top")
		(33 "B.Fab" user "Ref Des/Assembly Bottom")
	)
	(footprint ""
		(layer "F.Cu")
		(at -0.324612 -117.874034)
		(property "Reference" "R10W6"
			(at -0.8382 -0.67818 0)
			(unlocked yes)
			(layer "F.SilkS")
			(effects
				(font
					(size 0.4064 0.254)
					(thickness 0.1524)
				)
				(justify left)
			)
		)
		(property "Value" ""
			(at 0 0 0)
			(layer "F.Fab")
			(effects
				(font
					(size 1.27 1.27)
				)
			)
		)
		(duplicate_pad_numbers_are_jumpers no)
		(fp_poly
			(pts
				(xy -0.2794 -0.1016) (xy 0.2794 -0.1016) (xy 0.2794 0.9906) (xy -0.2794 0.9906)
			)
			(stroke
				(width 0)
				(type default)
			)
			(fill no)
			(layer "F.CrtYd")
		)
		(fp_line
			(start -0.2794 -0.1016)
			(end -0.2794 0.9906)
			(stroke
				(width 0.1)
				(type default)
			)
			(layer "F.Fab")
		)
		(fp_line
			(start -0.2794 0.9906)
			(end 0.2794 0.9906)
			(stroke
				(width 0.1)
				(type default)
			)
			(layer "F.Fab")
		)
		(fp_line
			(start 0.2794 -0.1016)
			(end -0.2794 -0.1016)
			(stroke
				(width 0.1)
				(type default)
			)
			(layer "F.Fab")
		)
		(fp_line
			(start 0.2794 0.9906)
			(end 0.2794 -0.1016)
			(stroke
				(width 0.1)
				(type default)
			)
			(layer "F.Fab")
		)
		(pad "1" smd rect
			(at 0 0)
			(size 0.508 0.508)
			(layers "F.Cu" "F.Mask" "F.Paste")
			(net "PUMP_TACH1")
		)
		(pad "2" smd rect
			(at 0 0.889)
			(size 0.508 0.508)
			(layers "F.Cu" "F.Mask" "F.Paste")
			(net "PUMP_TACH1_R")
		)
		(zone
			(layer "F.Cu")
			(hatch none 0.5)
			(connect_pads
				(clearance 0)
			)
			(min_thickness 0.25)
			(keepout
				(tracks allowed)
				(vias not_allowed)
				(pads allowed)
				(copperpour not_allowed)
				(footprints allowed)
			)
			(placement
				(enabled no)
				(sheetname "")
			)
			(fill
				(thermal_gap 0.5)
				(thermal_bridge_width 0.5)
				(island_removal_mode 0)
			)
			(polygon
				(pts
					(xy -0.578612 -117.620034) (xy -0.070612 -117.620034) (xy -0.070612 -117.239034) (xy -0.578612 -117.239034)
				)
			)
		)
		(zone
			(layer "F.Cu")
			(hatch none 0.5)
			(connect_pads
				(clearance 0)
			)
			(min_thickness 0.25)
			(keepout
				(tracks not_allowed)
				(vias allowed)
				(pads allowed)
				(copperpour not_allowed)
				(footprints allowed)
			)
			(placement
				(enabled no)
				(sheetname "")
			)
			(fill
				(thermal_gap 0.5)
				(thermal_bridge_width 0.5)
				(island_removal_mode 0)
			)
			(polygon
				(pts
					(xy -0.578612 -117.239034) (xy -0.070612 -117.239034) (xy -0.070612 -117.620034) (xy -0.578612 -117.620034)
				)
			)
		)
	)
	(footprint ""
		(layer "F.Cu")
		(at 490.524546 -153.68016 90)
		(property "Reference" "R9A5"
			(at 0 0 90)
			(layer "F.SilkS")
			(hide yes)
			(effects
				(font
					(size 1.27 1.27)
				)
			)
		)
		(property "Value" ""
			(at 0 0 90)
			(layer "F.Fab")
			(effects
				(font
					(size 1.27 1.27)
				)
			)
		)
		(duplicate_pad_numbers_are_jumpers no)
		(fp_poly
			(pts
				(xy -0.2794 -0.1016) (xy 0.2794 -0.1016) (xy 0.2794 0.9906) (xy -0.2794 0.9906)
			)
			(stroke
				(width 0)
				(type default)
			)
			(fill no)
			(layer "F.CrtYd")
		)
		(fp_line
			(start 0.2794 -0.1016)
			(end -0.2794 -0.1016)
			(stroke
				(width 0.1)
				(type default)
			)
			(layer "F.Fab")
		)
		(fp_line
			(start -0.2794 -0.1016)
			(end -0.2794 0.9906)
			(stroke
				(width 0.1)
				(type default)
			)
			(layer "F.Fab")
		)
		(fp_line
			(start 0.2794 0.9906)
			(end 0.2794 -0.1016)
			(stroke
				(width 0.1)
				(type default)
			)
			(layer "F.Fab")
		)
		(fp_line
			(start -0.2794 0.9906)
			(end 0.2794 0.9906)
			(stroke
				(width 0.1)
				(type default)
			)
			(layer "F.Fab")
		)
		(pad "1" smd rect
			(at 0 0 90)
			(size 0.508 0.508)
			(layers "F.Cu" "F.Mask" "F.Paste")
			(net "P5V_STBY")
		)
		(pad "2" smd rect
			(at 0 0.889 90)
			(size 0.508 0.508)
			(layers "F.Cu" "F.Mask" "F.Paste")
			(net "FM_UART_SWITCH_N")
		)
		(zone
			(layer "F.Cu")
			(hatch none 0.5)
			(connect_pads
				(clearance 0)
			)
			(min_thickness 0.25)
			(keepout
				(tracks allowed)
				(vias not_allowed)
				(pads allowed)
				(copperpour not_allowed)
				(footprints allowed)
			)
			(placement
				(enabled no)
				(sheetname "")
			)
			(fill
				(thermal_gap 0.5)
				(thermal_bridge_width 0.5)
				(island_removal_mode 0)
			)
			(polygon
				(pts
					(xy 490.778546 -153.42616) (xy 490.778546 -153.93416) (xy 491.159546 -153.93416) (xy 491.159546 -153.42616)
				)
			)
		)
		(zone
			(layer "F.Cu")
			(hatch none 0.5)
			(connect_pads
				(clearance 0)
			)
			(min_thickness 0.25)
			(keepout
				(tracks not_allowed)
				(vias allowed)
				(pads allowed)
				(copperpour not_allowed)
				(footprints allowed)
			)
			(placement
				(enabled no)
				(sheetname "")
			)
			(fill
				(thermal_gap 0.5)
				(thermal_bridge_width 0.5)
				(island_removal_mode 0)
			)
			(polygon
				(pts
					(xy 491.159546 -153.42616) (xy 491.159546 -153.93416) (xy 490.778546 -153.93416) (xy 490.778546 -153.42616)
				)
			)
		)
	)
	(footprint ""
		(layer "F.Cu")
		(at -3.175 -135.7122 -90)
		(property "Reference" "R1A3"
			(at 0 0 270)
			(layer "F.SilkS")
			(hide yes)
			(effects
				(font
					(size 1.27 1.27)
				)
			)
		)
		(property "Value" ""
			(at 0 0 270)
			(layer "F.Fab")
			(effects
				(font
					(size 1.27 1.27)
				)
			)
		)
		(duplicate_pad_numbers_are_jumpers no)
		(fp_poly
			(pts
				(xy -0.2794 -0.1016) (xy 0.2794 -0.1016) (xy 0.2794 0.9906) (xy -0.2794 0.9906)
			)
			(stroke
				(width 0)
				(type default)
			)
			(fill no)
			(layer "F.CrtYd")
		)
		(fp_line
			(start -0.2794 0.9906)
			(end 0.2794 0.9906)
			(stroke
				(width 0.1)
				(type default)
			)
			(layer "F.Fab")
		)
		(fp_line
			(start 0.2794 0.9906)
			(end 0.2794 -0.1016)
			(stroke
				(width 0.1)
				(type default)
			)
			(layer "F.Fab")
		)
		(fp_line
			(start -0.2794 -0.1016)
			(end -0.2794 0.9906)
			(stroke
				(width 0.1)
				(type default)
			)
			(layer "F.Fab")
		)
		(fp_line
			(start 0.2794 -0.1016)
			(end -0.2794 -0.1016)
			(stroke
				(width 0.1)
				(type default)
			)
			(layer "F.Fab")
		)
		(pad "1" smd rect
			(at 0 0 270)
			(size 0.508 0.508)
			(layers "F.Cu" "F.Mask" "F.Paste")
			(net "VR_PVDDQ_KLM_PH1_OCSET")
		)
		(pad "2" smd rect
			(at 0 0.889 270)
			(size 0.508 0.508)
			(layers "F.Cu" "F.Mask" "F.Paste")
			(net "GND")
		)
		(zone
			(layer "F.Cu")
			(hatch none 0.5)
			(connect_pads
				(clearance 0)
			)
			(min_thickness 0.25)
			(keepout
				(tracks not_allowed)
				(vias allowed)
				(pads allowed)
				(copperpour not_allowed)
				(footprints allowed)
			)
			(placement
				(enabled no)
				(sheetname "")
			)
			(fill
				(thermal_gap 0.5)
				(thermal_bridge_width 0.5)
				(island_removal_mode 0)
			)
			(polygon
				(pts
					(xy -3.81 -135.9662) (xy -3.81 -135.4582) (xy -3.429 -135.4582) (xy -3.429 -135.9662)
				)
			)
		)
		(zone
			(layer "F.Cu")
			(hatch none 0.5)
			(connect_pads
				(clearance 0)
			)
			(min_thickness 0.25)
			(keepout
				(tracks allowed)
				(vias not_allowed)
				(pads allowed)
				(copperpour not_allowed)
				(footprints allowed)
			)
			(placement
				(enabled no)
				(sheetname "")
			)
			(fill
				(thermal_gap 0.5)
				(thermal_bridge_width 0.5)
				(island_removal_mode 0)
			)
			(polygon
				(pts
					(xy -3.429 -135.9662) (xy -3.429 -135.4582) (xy -3.81 -135.4582) (xy -3.81 -135.9662)
				)
			)
		)
	)
)
